(kicad_pcb
	(version 20241229)
	(generator "pcbnew")
	(generator_version "9.0")
	(general
		(thickness 1.552)
		(legacy_teardrops no)
	)
	(paper "A4")
	(title_block
		(date "2023-07-25")
		(rev "1.1.4")
		(comment 9 "footprints 110-114 of 379")
	)
	(layers
		(0 "F.Cu" signal)
		(4 "In1.Cu" signal)
		(6 "In2.Cu" signal)
		(8 "In3.Cu" signal)
		(10 "In4.Cu" signal)
		(12 "In5.Cu" signal)
		(14 "In6.Cu" signal)
		(2 "B.Cu" signal)
		(9 "F.Adhes" user "F.Adhesive")
		(11 "B.Adhes" user "B.Adhesive")
		(13 "F.Paste" user)
		(15 "B.Paste" user)
		(5 "F.SilkS" user "F.Silkscreen")
		(7 "B.SilkS" user "B.Silkscreen")
		(1 "F.Mask" user)
		(3 "B.Mask" user)
		(17 "Dwgs.User" user "User.Drawings")
		(19 "Cmts.User" user "User.Comments")
		(21 "Eco1.User" user "User.Eco1")
		(23 "Eco2.User" user "User.Eco2")
		(25 "Edge.Cuts" user)
		(27 "Margin" user)
		(31 "F.CrtYd" user "F.Courtyard")
		(29 "B.CrtYd" user "B.Courtyard")
		(35 "F.Fab" user)
		(33 "B.Fab" user)
	)
	(footprint "antmicro-footprints:R_0402_1005Metric"
		(layer "F.Cu")
		(at 132.75 116.75 -90)
		(descr "Resistor SMD 0402")
		(tags "resistor SMD 0402")
		(property "Reference" "R126"
			(at -0.76 -0.28 270)
			(layer "F.SilkS")
			(effects
				(font
					(size 0.65 0.65)
					(thickness 0.15)
				)
				(justify left bottom)
			)
		)
		(property "Value" "R_0R_0402"
			(at 0 1.4 270)
			(layer "F.Fab")
			(hide yes)
			(effects
				(font
					(size 0.7 0.7)
					(thickness 0.15)
				)
				(justify left bottom)
			)
		)
		(property "Datasheet" "https://industrial.panasonic.com/cdbs/www-data/pdf/RDA0000/AOA0000C301.pdf"
			(at 0 0 270)
			(layer "F.Fab")
			(hide yes)
			(effects
				(font
					(size 1.27 1.27)
					(thickness 0.15)
				)
			)
		)
		(property "Description" "SMD Chip Resistor, Jumper, 0 ohm, 100 mW, 0402 [1005 Metric], Thick Film, General Purpose"
			(at 0 0 270)
			(layer "F.Fab")
			(hide yes)
			(effects
				(font
					(size 1.27 1.27)
					(thickness 0.15)
				)
			)
		)
		(property "Author" "Antmicro"
			(at 16 249.5 0)
			(layer "F.Fab")
			(hide yes)
			(effects
				(font
					(size 1 1)
					(thickness 0.15)
				)
			)
		)
		(property "Current" "1A"
			(at 16 249.5 0)
			(layer "F.Fab")
			(hide yes)
			(effects
				(font
					(size 1 1)
					(thickness 0.15)
				)
			)
		)
		(property "License" "Apache-2.0"
			(at 16 249.5 0)
			(layer "F.Fab")
			(hide yes)
			(effects
				(font
					(size 1 1)
					(thickness 0.15)
				)
			)
		)
		(property "MPN" "ERJ2GE0R00X"
			(at 16 249.5 0)
			(layer "F.Fab")
			(hide yes)
			(effects
				(font
					(size 1 1)
					(thickness 0.15)
				)
			)
		)
		(property "Manufacturer" "Panasonic"
			(at 16 249.5 0)
			(layer "F.Fab")
			(hide yes)
			(effects
				(font
					(size 1 1)
					(thickness 0.15)
				)
			)
		)
		(property "Tolerance" "~"
			(at 16 249.5 0)
			(layer "F.Fab")
			(hide yes)
			(effects
				(font
					(size 1 1)
					(thickness 0.15)
				)
			)
		)
		(property "Val" "0R"
			(at 16 249.5 0)
			(layer "F.Fab")
			(hide yes)
			(effects
				(font
					(size 1 1)
					(thickness 0.15)
				)
			)
		)
		(sheetname "/Peripherals/")
		(sheetfile "peripherals.kicad_sch")
		(attr smd)
		(fp_rect
			(start -0.925 -0.47)
			(end 0.925 0.47)
			(stroke
				(width 0.05)
				(type default)
			)
			(fill no)
			(layer "F.CrtYd")
		)
		(fp_rect
			(start -0.5 -0.25)
			(end 0.5 0.25)
			(stroke
				(width 0.15)
				(type solid)
			)
			(fill no)
			(layer "F.Fab")
		)
		(fp_text user "Author: Antmicro"
			(at -0.95 4.169 270)
			(layer "F.Fab")
			(effects
				(font
					(size 0.7 0.7)
					(thickness 0.15)
				)
				(justify left bottom)
			)
		)
		(fp_text user "License: Apache-2.0"
			(at -0.95 5.169 270)
			(layer "F.Fab")
			(effects
				(font
					(size 0.7 0.7)
					(thickness 0.15)
				)
				(justify left bottom)
			)
		)
		(fp_text user "${REFERENCE}"
			(at -0.95 3.168 270)
			(layer "F.Fab")
			(effects
				(font
					(size 0.7 0.7)
					(thickness 0.15)
				)
				(justify left bottom)
			)
		)
		(pad "1" smd roundrect
			(at -0.48 0 270)
			(size 0.59 0.64)
			(layers "F.Cu" "F.Mask" "F.Paste")
			(roundrect_rratio 0.25)
			(net 99 "/Peripherals/FCC2_SDA2")
			(pintype "passive")
		)
		(pad "2" smd roundrect
			(at 0.48 0 270)
			(size 0.59 0.64)
			(layers "F.Cu" "F.Mask" "F.Paste")
			(roundrect_rratio 0.25)
			(net 346 "Net-(J6-Pad41)")
			(pintype "passive")
		)
	)
	(footprint "antmicro-footprints:R_0402_1005Metric"
		(layer "F.Cu")
		(at 122.03 108.65 180)
		(descr "Resistor SMD 0402")
		(tags "resistor SMD 0402")
		(property "Reference" "R86"
			(at 0.95 -0.39 0)
			(layer "F.SilkS")
			(effects
				(font
					(size 0.65 0.65)
					(thickness 0.15)
				)
				(justify right bottom)
			)
		)
		(property "Value" "R_0R_0402"
			(at 0 1.4 0)
			(layer "F.Fab")
			(hide yes)
			(effects
				(font
					(size 0.7 0.7)
					(thickness 0.15)
				)
				(justify right bottom)
			)
		)
		(property "Datasheet" "https://industrial.panasonic.com/cdbs/www-data/pdf/RDA0000/AOA0000C301.pdf"
			(at 0 0 180)
			(layer "F.Fab")
			(hide yes)
			(effects
				(font
					(size 1.27 1.27)
					(thickness 0.15)
				)
			)
		)
		(property "Description" "SMD Chip Resistor, Jumper, 0 ohm, 100 mW, 0402 [1005 Metric], Thick Film, General Purpose"
			(at 0 0 180)
			(layer "F.Fab")
			(hide yes)
			(effects
				(font
					(size 1.27 1.27)
					(thickness 0.15)
				)
			)
		)
		(property "Author" "Antmicro"
			(at 244.06 217.3 0)
			(layer "F.Fab")
			(hide yes)
			(effects
				(font
					(size 1 1)
					(thickness 0.15)
				)
			)
		)
		(property "Current" "1A"
			(at 244.06 217.3 0)
			(layer "F.Fab")
			(hide yes)
			(effects
				(font
					(size 1 1)
					(thickness 0.15)
				)
			)
		)
		(property "License" "Apache-2.0"
			(at 244.06 217.3 0)
			(layer "F.Fab")
			(hide yes)
			(effects
				(font
					(size 1 1)
					(thickness 0.15)
				)
			)
		)
		(property "MPN" "ERJ2GE0R00X"
			(at 244.06 217.3 0)
			(layer "F.Fab")
			(hide yes)
			(effects
				(font
					(size 1 1)
					(thickness 0.15)
				)
			)
		)
		(property "Manufacturer" "Panasonic"
			(at 244.06 217.3 0)
			(layer "F.Fab")
			(hide yes)
			(effects
				(font
					(size 1 1)
					(thickness 0.15)
				)
			)
		)
		(property "Tolerance" "~"
			(at 244.06 217.3 0)
			(layer "F.Fab")
			(hide yes)
			(effects
				(font
					(size 1 1)
					(thickness 0.15)
				)
			)
		)
		(property "Val" "0R"
			(at 244.06 217.3 0)
			(layer "F.Fab")
			(hide yes)
			(effects
				(font
					(size 1 1)
					(thickness 0.15)
				)
			)
		)
		(sheetname "/FPGA/")
		(sheetfile "fpga.kicad_sch")
		(attr smd)
		(fp_rect
			(start -0.925 -0.47)
			(end 0.925 0.47)
			(stroke
				(width 0.05)
				(type default)
			)
			(fill no)
			(layer "F.CrtYd")
		)
		(fp_rect
			(start -0.5 -0.25)
			(end 0.5 0.25)
			(stroke
				(width 0.15)
				(type solid)
			)
			(fill no)
			(layer "F.Fab")
		)
		(fp_text user "${REFERENCE}"
			(at -0.95 3.168 180)
			(layer "F.Fab")
			(effects
				(font
					(size 0.7 0.7)
					(thickness 0.15)
				)
				(justify left bottom)
			)
		)
		(fp_text user "License: Apache-2.0"
			(at -0.95 5.169 180)
			(layer "F.Fab")
			(effects
				(font
					(size 0.7 0.7)
					(thickness 0.15)
				)
				(justify left bottom)
			)
		)
		(fp_text user "Author: Antmicro"
			(at -0.95 4.169 180)
			(layer "F.Fab")
			(effects
				(font
					(size 0.7 0.7)
					(thickness 0.15)
				)
				(justify left bottom)
			)
		)
		(pad "1" smd roundrect
			(at -0.48 0 180)
			(size 0.59 0.64)
			(layers "F.Cu" "F.Mask" "F.Paste")
			(roundrect_rratio 0.25)
			(net 15 "/FPGA/INITN")
			(pintype "passive")
		)
		(pad "2" smd roundrect
			(at 0.48 0 180)
			(size 0.59 0.64)
			(layers "F.Cu" "F.Mask" "F.Paste")
			(roundrect_rratio 0.25)
			(net 42 "/FPGA/INITN_SOFT")
			(pintype "passive")
		)
	)
	(footprint "antmicro-footprints:C_0603_1608Metric"
		(layer "F.Cu")
		(at 147.63 70.85 -90)
		(descr "Capacitor SMD 0603")
		(tags "capacitor 0603")
		(property "Reference" "C23"
			(at 0.59 0.9 90)
			(layer "F.SilkS")
			(effects
				(font
					(size 0.65 0.65)
					(thickness 0.15)
				)
				(justify right bottom)
			)
		)
		(property "Value" "C_22u_0603"
			(at 0 1.6 90)
			(layer "F.Fab")
			(hide yes)
			(effects
				(font
					(size 0.7 0.7)
					(thickness 0.15)
				)
				(justify right bottom)
			)
		)
		(property "Datasheet" "https://www.murata.com/products/productdetail?partno=GRM188R60J226MEA0%23"
			(at 0 0 270)
			(layer "F.Fab")
			(hide yes)
			(effects
				(font
					(size 1.27 1.27)
					(thickness 0.15)
				)
			)
		)
		(property "Description" "SMD Multilayer Ceramic Capacitor, 22 µF, 6.3 V, 0603 [1608 Metric], ± 20%, X5R, GRM Series"
			(at 0 0 270)
			(layer "F.Fab")
			(hide yes)
			(effects
				(font
					(size 1.27 1.27)
					(thickness 0.15)
				)
			)
		)
		(property "Author" "Antmicro"
			(at 76.78 218.48 0)
			(layer "F.Fab")
			(hide yes)
			(effects
				(font
					(size 1 1)
					(thickness 0.15)
				)
			)
		)
		(property "Dielectric" ""
			(at 76.78 218.48 0)
			(layer "F.Fab")
			(hide yes)
			(effects
				(font
					(size 1 1)
					(thickness 0.15)
				)
			)
		)
		(property "License" "Apache-2.0"
			(at 76.78 218.48 0)
			(layer "F.Fab")
			(hide yes)
			(effects
				(font
					(size 1 1)
					(thickness 0.15)
				)
			)
		)
		(property "MPN" "GRM188R60J226MEA0D"
			(at 76.78 218.48 0)
			(layer "F.Fab")
			(hide yes)
			(effects
				(font
					(size 1 1)
					(thickness 0.15)
				)
			)
		)
		(property "Manufacturer" "Murata"
			(at 76.78 218.48 0)
			(layer "F.Fab")
			(hide yes)
			(effects
				(font
					(size 1 1)
					(thickness 0.15)
				)
			)
		)
		(property "Val" "22u"
			(at 76.78 218.48 0)
			(layer "F.Fab")
			(hide yes)
			(effects
				(font
					(size 1 1)
					(thickness 0.15)
				)
			)
		)
		(property "Voltage" ""
			(at 76.78 218.48 0)
			(layer "F.Fab")
			(hide yes)
			(effects
				(font
					(size 1 1)
					(thickness 0.15)
				)
			)
		)
		(sheetname "/Power Supply/")
		(sheetfile "supply.kicad_sch")
		(attr smd)
		(fp_line
			(start -0.15 0.4)
			(end 0.15 0.4)
			(stroke
				(width 0.15)
				(type solid)
			)
			(layer "F.SilkS")
		)
		(fp_line
			(start -0.15 -0.4)
			(end 0.15 -0.4)
			(stroke
				(width 0.15)
				(type solid)
			)
			(layer "F.SilkS")
		)
		(fp_rect
			(start -1.25 -0.65)
			(end 1.25 0.65)
			(stroke
				(width 0.05)
				(type solid)
			)
			(fill no)
			(layer "F.CrtYd")
		)
		(fp_rect
			(start -0.8 -0.4)
			(end 0.8 0.4)
			(stroke
				(width 0.15)
				(type solid)
			)
			(fill no)
			(layer "F.Fab")
		)
		(fp_text user "License: Apache-2.0"
			(at -1.682 5.895 270)
			(layer "F.Fab")
			(effects
				(font
					(size 0.7 0.7)
					(thickness 0.15)
				)
				(justify left bottom)
			)
		)
		(fp_text user "${REFERENCE}"
			(at -1.682 3.895 270)
			(layer "F.Fab")
			(effects
				(font
					(size 0.7 0.7)
					(thickness 0.15)
				)
				(justify left bottom)
			)
		)
		(fp_text user "Author: Antmicro"
			(at -1.682 4.894 270)
			(layer "F.Fab")
			(effects
				(font
					(size 0.7 0.7)
					(thickness 0.15)
				)
				(justify left bottom)
			)
		)
		(pad "1" smd roundrect
			(at -0.7 0 270)
			(size 0.8 1)
			(layers "F.Cu" "F.Mask" "F.Paste")
			(roundrect_rratio 0.2)
			(net 1 "GND")
			(pintype "passive")
		)
		(pad "2" smd roundrect
			(at 0.7 0 270)
			(size 0.8 1)
			(layers "F.Cu" "F.Mask" "F.Paste")
			(roundrect_rratio 0.2)
			(net 273 "/Power Supply/1V0_OUT")
			(pintype "passive")
		)
	)
	(footprint "antmicro-footprints:C_0603_1608Metric"
		(layer "F.Cu")
		(at 167.03 86.15 90)
		(descr "Capacitor SMD 0603")
		(tags "capacitor 0603")
		(property "Reference" "C112"
			(at -1.49 1.5 90)
			(layer "F.SilkS")
			(effects
				(font
					(size 0.65 0.65)
					(thickness 0.15)
				)
				(justify left bottom)
			)
		)
		(property "Value" "C_1u_0603"
			(at 0 1.6 90)
			(layer "F.Fab")
			(hide yes)
			(effects
				(font
					(size 0.7 0.7)
					(thickness 0.15)
				)
				(justify left bottom)
			)
		)
		(property "Datasheet" "https://spicat.kyocera-avx.com/product/mlcc/chartview/0603YD105KAT2A/"
			(at 0 0 90)
			(layer "F.Fab")
			(hide yes)
			(effects
				(font
					(size 1.27 1.27)
					(thickness 0.15)
				)
			)
		)
		(property "Description" "SMD Multilayer Ceramic Capacitor, 1 µF, 16 V, 0603 [1608 Metric], ± 10%, X5R, AVX 0603 MLCC"
			(at 0 0 90)
			(layer "F.Fab")
			(hide yes)
			(effects
				(font
					(size 1.27 1.27)
					(thickness 0.15)
				)
			)
		)
		(property "Author" "Antmicro"
			(at 253.18 -80.88 0)
			(layer "F.Fab")
			(hide yes)
			(effects
				(font
					(size 1 1)
					(thickness 0.15)
				)
			)
		)
		(property "Dielectric" ""
			(at 253.18 -80.88 0)
			(layer "F.Fab")
			(hide yes)
			(effects
				(font
					(size 1 1)
					(thickness 0.15)
				)
			)
		)
		(property "License" "Apache-2.0"
			(at 253.18 -80.88 0)
			(layer "F.Fab")
			(hide yes)
			(effects
				(font
					(size 1 1)
					(thickness 0.15)
				)
			)
		)
		(property "MPN" "0603YD105KAT2A"
			(at 253.18 -80.88 0)
			(layer "F.Fab")
			(hide yes)
			(effects
				(font
					(size 1 1)
					(thickness 0.15)
				)
			)
		)
		(property "Manufacturer" "KYOCERA AVX"
			(at 253.18 -80.88 0)
			(layer "F.Fab")
			(hide yes)
			(effects
				(font
					(size 1 1)
					(thickness 0.15)
				)
			)
		)
		(property "Val" "1u"
			(at 253.18 -80.88 0)
			(layer "F.Fab")
			(hide yes)
			(effects
				(font
					(size 1 1)
					(thickness 0.15)
				)
			)
		)
		(property "Voltage" ""
			(at 253.18 -80.88 0)
			(layer "F.Fab")
			(hide yes)
			(effects
				(font
					(size 1 1)
					(thickness 0.15)
				)
			)
		)
		(sheetname "/Peripherals/")
		(sheetfile "peripherals.kicad_sch")
		(attr smd)
		(fp_line
			(start -0.15 -0.4)
			(end 0.15 -0.4)
			(stroke
				(width 0.15)
				(type solid)
			)
			(layer "F.SilkS")
		)
		(fp_line
			(start -0.15 0.4)
			(end 0.15 0.4)
			(stroke
				(width 0.15)
				(type solid)
			)
			(layer "F.SilkS")
		)
		(fp_rect
			(start -1.25 -0.65)
			(end 1.25 0.65)
			(stroke
				(width 0.05)
				(type solid)
			)
			(fill no)
			(layer "F.CrtYd")
		)
		(fp_rect
			(start -0.8 -0.4)
			(end 0.8 0.4)
			(stroke
				(width 0.15)
				(type solid)
			)
			(fill no)
			(layer "F.Fab")
		)
		(fp_text user "Author: Antmicro"
			(at -1.682 4.894 90)
			(layer "F.Fab")
			(effects
				(font
					(size 0.7 0.7)
					(thickness 0.15)
				)
				(justify left bottom)
			)
		)
		(fp_text user "${REFERENCE}"
			(at -1.682 3.895 90)
			(layer "F.Fab")
			(effects
				(font
					(size 0.7 0.7)
					(thickness 0.15)
				)
				(justify left bottom)
			)
		)
		(fp_text user "License: Apache-2.0"
			(at -1.682 5.895 90)
			(layer "F.Fab")
			(effects
				(font
					(size 0.7 0.7)
					(thickness 0.15)
				)
				(justify left bottom)
			)
		)
		(pad "1" smd roundrect
			(at -0.7 0 90)
			(size 0.8 1)
			(layers "F.Cu" "F.Mask" "F.Paste")
			(roundrect_rratio 0.2)
			(net 1 "GND")
			(pintype "passive")
		)
		(pad "2" smd roundrect
			(at 0.7 0 90)
			(size 0.8 1)
			(layers "F.Cu" "F.Mask" "F.Paste")
			(roundrect_rratio 0.2)
			(net 16 "/Peripherals/FFC1_5V")
			(pintype "passive")
		)
	)
	(footprint "antmicro-footprints:R_0402_1005Metric"
		(layer "F.Cu")
		(at 113.4 85.6)
		(descr "Resistor SMD 0402")
		(tags "resistor SMD 0402")
		(property "Reference" "R39"
			(at -1.17 -0.66 0)
			(layer "F.SilkS")
			(effects
				(font
					(size 0.65 0.65)
					(thickness 0.15)
				)
				(justify left bottom)
			)
		)
		(property "Value" "R_0R_0402"
			(at 0 1.4 0)
			(layer "F.Fab")
			(hide yes)
			(effects
				(font
					(size 0.7 0.7)
					(thickness 0.15)
				)
				(justify left bottom)
			)
		)
		(property "Datasheet" "https://industrial.panasonic.com/cdbs/www-data/pdf/RDA0000/AOA0000C301.pdf"
			(at 0 0 0)
			(layer "F.Fab")
			(hide yes)
			(effects
				(font
					(size 1.27 1.27)
					(thickness 0.15)
				)
			)
		)
		(property "Description" "SMD Chip Resistor, Jumper, 0 ohm, 100 mW, 0402 [1005 Metric], Thick Film, General Purpose"
			(at 0 0 0)
			(layer "F.Fab")
			(hide yes)
			(effects
				(font
					(size 1.27 1.27)
					(thickness 0.15)
				)
			)
		)
		(property "Author" "Antmicro"
			(at 0 0 0)
			(layer "F.Fab")
			(hide yes)
			(effects
				(font
					(size 1 1)
					(thickness 0.15)
				)
			)
		)
		(property "Current" "1A"
			(at 0 0 0)
			(layer "F.Fab")
			(hide yes)
			(effects
				(font
					(size 1 1)
					(thickness 0.15)
				)
			)
		)
		(property "License" "Apache-2.0"
			(at 0 0 0)
			(layer "F.Fab")
			(hide yes)
			(effects
				(font
					(size 1 1)
					(thickness 0.15)
				)
			)
		)
		(property "MPN" "ERJ2GE0R00X"
			(at 0 0 0)
			(layer "F.Fab")
			(hide yes)
			(effects
				(font
					(size 1 1)
					(thickness 0.15)
				)
			)
		)
		(property "Manufacturer" "Panasonic"
			(at 0 0 0)
			(layer "F.Fab")
			(hide yes)
			(effects
				(font
					(size 1 1)
					(thickness 0.15)
				)
			)
		)
		(property "Tolerance" "~"
			(at 0 0 0)
			(layer "F.Fab")
			(hide yes)
			(effects
				(font
					(size 1 1)
					(thickness 0.15)
				)
			)
		)
		(property "Val" "0R"
			(at 0 0 0)
			(layer "F.Fab")
			(hide yes)
			(effects
				(font
					(size 1 1)
					(thickness 0.15)
				)
			)
		)
		(sheetname "/FPGA/")
		(sheetfile "fpga.kicad_sch")
		(attr smd)
		(fp_rect
			(start -0.925 -0.47)
			(end 0.925 0.47)
			(stroke
				(width 0.05)
				(type default)
			)
			(fill no)
			(layer "F.CrtYd")
		)
		(fp_rect
			(start -0.5 -0.25)
			(end 0.5 0.25)
			(stroke
				(width 0.15)
				(type solid)
			)
			(fill no)
			(layer "F.Fab")
		)
		(fp_text user "${REFERENCE}"
			(at -0.95 3.168 0)
			(layer "F.Fab")
			(effects
				(font
					(size 0.7 0.7)
					(thickness 0.15)
				)
				(justify left bottom)
			)
		)
		(fp_text user "Author: Antmicro"
			(at -0.95 4.169 0)
			(layer "F.Fab")
			(effects
				(font
					(size 0.7 0.7)
					(thickness 0.15)
				)
				(justify left bottom)
			)
		)
		(fp_text user "License: Apache-2.0"
			(at -0.95 5.169 0)
			(layer "F.Fab")
			(effects
				(font
					(size 0.7 0.7)
					(thickness 0.15)
				)
				(justify left bottom)
			)
		)
		(pad "1" smd roundrect
			(at -0.48 0)
			(size 0.59 0.64)
			(layers "F.Cu" "F.Mask" "F.Paste")
			(roundrect_rratio 0.25)
			(net 286 "Net-(Y2-EN)")
			(pintype "passive")
		)
		(pad "2" smd roundrect
			(at 0.48 0)
			(size 0.59 0.64)
			(layers "F.Cu" "F.Mask" "F.Paste")
			(roundrect_rratio 0.25)
			(net 2 "+3V3")
			(pintype "passive")
		)
	)
)
